# BASEBOARD_FAB2 (Tioga Pass) — schematic netlist excerpt (pin names and nets, part order shuffled) for the footprints in the layout excerpt that follows; sources: Cadence DE-HDL packaged netlist, KiCad conversion of Wiwynn_Tioga_Pass_MB.brd

R2P8  RES  4.75K 1% CHIP  pkg 0402  page 170 : A = P3V3_STBY ; B = IRQ_SML1_PMBUS_ALERT_N
C8E16  CAP  270PF 50V 10% X7R  pkg 0402LF  page 241 : A = VR_P5V_STBY_COMP ; B = AGND_P5V_STBY
C2D39  CAP_A  22.0UF 4V 20% X6S  pkg 0603V  page 76 : A = PVCCMCP_CPU1 ; B = GND

(kicad_pcb
	(version 20260206)
	(generator "pcbnew")
	(generator_version "10.0")
	(general
		(thickness 1.6)
		(legacy_teardrops no)
	)
	(paper "A4")
	(title_block
		(title "Wiwynn_Tioga_Pass_MB.brd")
		(comment 1 "Tioga Pass / footprints 353-355 of 4770")
	)
	(layers
		(0 "F.Cu" signal "TOP")
		(4 "In1.Cu" signal "L2GND")
		(6 "In2.Cu" signal "L3")
		(8 "In3.Cu" signal "L4GND")
		(10 "In4.Cu" signal "L5")
		(12 "In5.Cu" signal "L6GND")
		(14 "In6.Cu" signal "L7VCC")
		(16 "In7.Cu" signal "L8VCC")
		(18 "In8.Cu" signal "L9GND")
		(20 "In9.Cu" signal "L10")
		(22 "In10.Cu" signal "L11GND")
		(24 "In11.Cu" signal "L12")
		(26 "In12.Cu" signal "L13GND")
		(2 "B.Cu" signal "BOTTOM")
		(9 "F.Adhes" user "F.Adhesive")
		(11 "B.Adhes" user "B.Adhesive")
		(13 "F.Paste" user "Package Geometry/Pastemask Top")
		(15 "B.Paste" user "Package Geometry/Pastemask Bottom")
		(5 "F.SilkS" user "Ref Des/Silkscreen Top")
		(7 "B.SilkS" user "Ref Des/Silkscreen Bottom")
		(1 "F.Mask" user "Board Geometry/Soldermask Top")
		(3 "B.Mask" user "Board Geometry/Soldermask Bottom")
		(17 "Dwgs.User" user "User.Drawings")
		(19 "Cmts.User" user "User.Comments")
		(21 "Eco1.User" user "User.Eco1")
		(23 "Eco2.User" user "User.Eco2")
		(25 "Edge.Cuts" user "Board Geometry/Outline")
		(27 "Margin" user)
		(31 "F.CrtYd" user "Package Geometry/Place Bound Top")
		(29 "B.CrtYd" user "Package Geometry/Place Bound Bottom")
		(35 "F.Fab" user "Ref Des/Assembly Top")
		(33 "B.Fab" user "Ref Des/Assembly Bottom")
	)
	(footprint ""
		(layer "F.Cu")
		(at 416.814 -82.55 90)
		(property "Reference" "R2P8"
			(at 0 0 90)
			(layer "F.SilkS")
			(hide yes)
			(effects
				(font
					(size 1.27 1.27)
				)
			)
		)
		(property "Value" ""
			(at 0 0 90)
			(layer "F.Fab")
			(effects
				(font
					(size 1.27 1.27)
				)
			)
		)
		(duplicate_pad_numbers_are_jumpers no)
		(fp_poly
			(pts
				(xy -0.2794 -0.1016) (xy 0.2794 -0.1016) (xy 0.2794 0.9906) (xy -0.2794 0.9906)
			)
			(stroke
				(width 0)
				(type default)
			)
			(fill no)
			(layer "F.CrtYd")
		)
		(fp_line
			(start 0.2794 -0.1016)
			(end -0.2794 -0.1016)
			(stroke
				(width 0.1)
				(type default)
			)
			(layer "F.Fab")
		)
		(fp_line
			(start -0.2794 -0.1016)
			(end -0.2794 0.9906)
			(stroke
				(width 0.1)
				(type default)
			)
			(layer "F.Fab")
		)
		(fp_line
			(start 0.2794 0.9906)
			(end 0.2794 -0.1016)
			(stroke
				(width 0.1)
				(type default)
			)
			(layer "F.Fab")
		)
		(fp_line
			(start -0.2794 0.9906)
			(end 0.2794 0.9906)
			(stroke
				(width 0.1)
				(type default)
			)
			(layer "F.Fab")
		)
		(pad "1" smd rect
			(at 0 0 90)
			(size 0.508 0.508)
			(layers "F.Cu" "F.Mask" "F.Paste")
			(net "P3V3_STBY")
		)
		(pad "2" smd rect
			(at 0 0.889 90)
			(size 0.508 0.508)
			(layers "F.Cu" "F.Mask" "F.Paste")
			(net "IRQ_SML1_PMBUS_ALERT_N")
		)
		(zone
			(layer "F.Cu")
			(hatch none 0.5)
			(connect_pads
				(clearance 0)
			)
			(min_thickness 0.25)
			(keepout
				(tracks allowed)
				(vias not_allowed)
				(pads allowed)
				(copperpour not_allowed)
				(footprints allowed)
			)
			(placement
				(enabled no)
				(sheetname "")
			)
			(fill
				(thermal_gap 0.5)
				(thermal_bridge_width 0.5)
				(island_removal_mode 0)
			)
			(polygon
				(pts
					(xy 417.068 -82.296) (xy 417.068 -82.804) (xy 417.449 -82.804) (xy 417.449 -82.296)
				)
			)
		)
		(zone
			(layer "F.Cu")
			(hatch none 0.5)
			(connect_pads
				(clearance 0)
			)
			(min_thickness 0.25)
			(keepout
				(tracks not_allowed)
				(vias allowed)
				(pads allowed)
				(copperpour not_allowed)
				(footprints allowed)
			)
			(placement
				(enabled no)
				(sheetname "")
			)
			(fill
				(thermal_gap 0.5)
				(thermal_bridge_width 0.5)
				(island_removal_mode 0)
			)
			(polygon
				(pts
					(xy 417.449 -82.296) (xy 417.449 -82.804) (xy 417.068 -82.804) (xy 417.068 -82.296)
				)
			)
		)
	)
	(footprint ""
		(layer "F.Cu")
		(at 104.35844 -73.279)
		(property "Reference" "C2D39"
			(at 0 0 0)
			(layer "F.SilkS")
			(hide yes)
			(effects
				(font
					(size 1.27 1.27)
				)
			)
		)
		(property "Value" ""
			(at 0 0 0)
			(layer "F.Fab")
			(effects
				(font
					(size 1.27 1.27)
				)
			)
		)
		(duplicate_pad_numbers_are_jumpers no)
		(fp_poly
			(pts
				(xy -0.4953 -0.2032) (xy 0.4953 -0.2032) (xy 0.4953 1.6002) (xy -0.4953 1.6002)
			)
			(stroke
				(width 0)
				(type default)
			)
			(fill no)
			(layer "F.CrtYd")
		)
		(fp_line
			(start -0.4953 -0.2032)
			(end 0.4953 -0.2032)
			(stroke
				(width 0.1)
				(type default)
			)
			(layer "F.Fab")
		)
		(fp_line
			(start -0.4953 1.6002)
			(end -0.4953 -0.2032)
			(stroke
				(width 0.1)
				(type default)
			)
			(layer "F.Fab")
		)
		(fp_line
			(start 0.4953 -0.2032)
			(end 0.4953 1.6002)
			(stroke
				(width 0.1)
				(type default)
			)
			(layer "F.Fab")
		)
		(fp_line
			(start 0.4953 1.6002)
			(end -0.4953 1.6002)
			(stroke
				(width 0.1)
				(type default)
			)
			(layer "F.Fab")
		)
		(pad "1" smd rect
			(at 0 0)
			(size 0.762 0.889)
			(layers "F.Cu" "F.Mask" "F.Paste")
			(net "PVCCMCP_CPU1")
		)
		(pad "2" smd rect
			(at 0 1.397)
			(size 0.762 0.889)
			(layers "F.Cu" "F.Mask" "F.Paste")
			(net "GND")
		)
		(zone
			(layer "F.Cu")
			(hatch none 0.5)
			(connect_pads
				(clearance 0)
			)
			(min_thickness 0.25)
			(keepout
				(tracks not_allowed)
				(vias allowed)
				(pads allowed)
				(copperpour not_allowed)
				(footprints allowed)
			)
			(placement
				(enabled no)
				(sheetname "")
			)
			(fill
				(thermal_gap 0.5)
				(thermal_bridge_width 0.5)
				(island_removal_mode 0)
			)
			(polygon
				(pts
					(xy 103.97744 -72.8345) (xy 104.73944 -72.8345) (xy 104.73944 -72.3265) (xy 103.97744 -72.3265)
				)
			)
		)
	)
	(footprint ""
		(layer "F.Cu")
		(at 392.023346 -64.7065)
		(property "Reference" "C8E16"
			(at 0 0 0)
			(layer "F.SilkS")
			(hide yes)
			(effects
				(font
					(size 1.27 1.27)
				)
			)
		)
		(property "Value" ""
			(at 0 0 0)
			(layer "F.Fab")
			(effects
				(font
					(size 1.27 1.27)
				)
			)
		)
		(duplicate_pad_numbers_are_jumpers no)
		(fp_poly
			(pts
				(xy 0.3048 -0.1016) (xy 0.3048 0.9906) (xy -0.3048 0.9906) (xy -0.3048 -0.1016)
			)
			(stroke
				(width 0)
				(type default)
			)
			(fill no)
			(layer "F.CrtYd")
		)
		(fp_line
			(start -0.3048 -0.1016)
			(end -0.3048 0.9906)
			(stroke
				(width 0.1)
				(type default)
			)
			(layer "F.Fab")
		)
		(fp_line
			(start -0.3048 0.9906)
			(end 0.3048 0.9906)
			(stroke
				(width 0.1)
				(type default)
			)
			(layer "F.Fab")
		)
		(fp_line
			(start 0.3048 -0.1016)
			(end -0.3048 -0.1016)
			(stroke
				(width 0.1)
				(type default)
			)
			(layer "F.Fab")
		)
		(fp_line
			(start 0.3048 0.9906)
			(end 0.3048 -0.1016)
			(stroke
				(width 0.1)
				(type default)
			)
			(layer "F.Fab")
		)
		(pad "1" smd rect
			(at 0 0)
			(size 0.508 0.508)
			(layers "F.Cu" "F.Mask" "F.Paste")
			(net "VR_P5V_STBY_COMP")
		)
		(pad "2" smd rect
			(at 0 0.889)
			(size 0.508 0.508)
			(layers "F.Cu" "F.Mask" "F.Paste")
			(net "AGND_P5V_STBY")
		)
		(zone
			(layer "F.Cu")
			(hatch none 0.5)
			(connect_pads
				(clearance 0)
			)
			(min_thickness 0.25)
			(keepout
				(tracks allowed)
				(vias not_allowed)
				(pads allowed)
				(copperpour not_allowed)
				(footprints allowed)
			)
			(placement
				(enabled no)
				(sheetname "")
			)
			(fill
				(thermal_gap 0.5)
				(thermal_bridge_width 0.5)
				(island_removal_mode 0)
			)
			(polygon
				(pts
					(xy 391.769346 -64.4525) (xy 392.277346 -64.4525) (xy 392.277346 -64.0715) (xy 391.769346 -64.0715)
				)
			)
		)
		(zone
			(layer "F.Cu")
			(hatch none 0.5)
			(connect_pads
				(clearance 0)
			)
			(min_thickness 0.25)
			(keepout
				(tracks not_allowed)
				(vias allowed)
				(pads allowed)
				(copperpour not_allowed)
				(footprints allowed)
			)
			(placement
				(enabled no)
				(sheetname "")
			)
			(fill
				(thermal_gap 0.5)
				(thermal_bridge_width 0.5)
				(island_removal_mode 0)
			)
			(polygon
				(pts
					(xy 391.769346 -64.0715) (xy 392.277346 -64.0715) (xy 392.277346 -64.4525) (xy 391.769346 -64.4525)
				)
			)
		)
	)
)
